G04*
G04 #@! TF.GenerationSoftware,Altium Limited,Altium Designer,23.6.0 (18)*
G04*
G04 Layer_Physical_Order=4*
G04 Layer_Color=16737945*
%FSLAX44Y44*%
%MOMM*%
G71*
G04*
G04 #@! TF.SameCoordinates,0D6CC9A4-690D-4EF8-AA6E-9FB67146BD04*
G04*
G04*
G04 #@! TF.FilePolarity,Positive*
G04*
G01*
G75*
%ADD76R,2.0200X2.0200*%
%ADD77C,2.0200*%
%ADD78C,2.0900*%
%ADD79C,5.3000*%
%ADD80C,0.6000*%
G36*
X503922Y502958D02*
X503922Y5000D01*
X503921Y4999D01*
X503290Y4368D01*
X502957Y4078D01*
X5000Y4078D01*
X4919D01*
X4078Y5042D01*
X4078Y350700D01*
X5348Y351226D01*
X5912Y350662D01*
X7750Y349901D01*
X9739D01*
X11577Y350662D01*
X12983Y352069D01*
X13744Y353906D01*
Y355895D01*
X12983Y357733D01*
X11577Y359140D01*
X9739Y359901D01*
X7750D01*
X5912Y359140D01*
X5348Y358576D01*
X4078Y359102D01*
Y502953D01*
X4746Y503699D01*
X5000Y503921D01*
X503000Y503922D01*
X503081D01*
X503922Y502958D01*
D02*
G37*
%LPC*%
G36*
X193522Y499450D02*
X190478D01*
X187493Y498856D01*
X184682Y497692D01*
X182348Y496132D01*
X181239Y495582D01*
X179832Y496989D01*
X177995Y497750D01*
X176005D01*
X174168Y496989D01*
X172761Y495582D01*
X171652Y496132D01*
X169318Y497692D01*
X166507Y498856D01*
X163522Y499450D01*
X160478D01*
X157493Y498856D01*
X154682Y497692D01*
X152151Y496001D01*
X149999Y493849D01*
X148308Y491318D01*
X147144Y488507D01*
X146550Y485522D01*
Y482478D01*
X147144Y479493D01*
X148308Y476682D01*
X149999Y474151D01*
X152151Y471999D01*
X154682Y470308D01*
X157493Y469144D01*
X160478Y468550D01*
X163522D01*
X166507Y469144D01*
X169318Y470308D01*
X171849Y471999D01*
X174001Y474151D01*
X175692Y476682D01*
X176313Y478181D01*
X177687D01*
X178308Y476682D01*
X179999Y474151D01*
X182151Y471999D01*
X184682Y470308D01*
X187493Y469144D01*
X190478Y468550D01*
X193522D01*
X196507Y469144D01*
X199318Y470308D01*
X201849Y471999D01*
X204001Y474151D01*
X205692Y476682D01*
X206856Y479493D01*
X207450Y482478D01*
Y484045D01*
X208505Y484750D01*
X210494D01*
X212332Y485511D01*
X213739Y486918D01*
X214500Y488755D01*
Y490745D01*
X213739Y492582D01*
X212332Y493989D01*
X210494Y494750D01*
X208505D01*
X206668Y493989D01*
X205928Y493250D01*
X204319Y493373D01*
X204001Y493849D01*
X201849Y496001D01*
X199318Y497692D01*
X196507Y498856D01*
X193522Y499450D01*
D02*
G37*
G36*
X118075Y498963D02*
X116086D01*
X114248Y498201D01*
X112842Y496795D01*
X112080Y494957D01*
Y493323D01*
X111022Y492726D01*
X110907Y492700D01*
X109644Y493963D01*
X106805Y495602D01*
X103639Y496450D01*
X100361D01*
X97194Y495602D01*
X94355Y493963D01*
X92037Y491645D01*
X90398Y488806D01*
X89550Y485639D01*
Y482361D01*
X89966Y480808D01*
X88902Y479874D01*
X87995Y480250D01*
X86005D01*
X85098Y479874D01*
X84034Y480808D01*
X84450Y482361D01*
Y485639D01*
X83602Y488806D01*
X81962Y491645D01*
X79644Y493963D01*
X76806Y495602D01*
X73639Y496450D01*
X70361D01*
X67194Y495602D01*
X64356Y493963D01*
X62038Y491645D01*
X60399Y488806D01*
X59550Y485639D01*
Y482361D01*
X60399Y479194D01*
X62038Y476356D01*
X64356Y474038D01*
X67194Y472398D01*
X70361Y471550D01*
X73639D01*
X76806Y472398D01*
X79644Y474038D01*
X80730Y475123D01*
X82000Y474597D01*
Y474255D01*
X82761Y472418D01*
X84168Y471011D01*
X86005Y470250D01*
X87995D01*
X89832Y471011D01*
X91239Y472418D01*
X92000Y474255D01*
Y474597D01*
X93270Y475123D01*
X94355Y474038D01*
X97194Y472398D01*
X100361Y471550D01*
X103639D01*
X106805Y472398D01*
X109644Y474038D01*
X111962Y476356D01*
X113602Y479194D01*
X114450Y482361D01*
Y485639D01*
X113636Y488676D01*
X113963Y489073D01*
X114629Y489566D01*
X116086Y488963D01*
X118075D01*
X119320Y489478D01*
X119775Y489194D01*
X120322Y488518D01*
X119550Y485639D01*
Y482361D01*
X120398Y479194D01*
X122037Y476356D01*
X124355Y474038D01*
X127194Y472398D01*
X130361Y471550D01*
X133639D01*
X136805Y472398D01*
X139644Y474038D01*
X141962Y476356D01*
X143602Y479194D01*
X144450Y482361D01*
Y485639D01*
X143602Y488806D01*
X141962Y491645D01*
X139644Y493963D01*
X136805Y495602D01*
X133639Y496450D01*
X130361D01*
X127194Y495602D01*
X124355Y493963D01*
X123343Y492950D01*
X122080Y493484D01*
Y494957D01*
X121319Y496795D01*
X119913Y498201D01*
X118075Y498963D01*
D02*
G37*
G36*
X299709Y494190D02*
X297720D01*
X295882Y493429D01*
X294476Y492022D01*
X293715Y490185D01*
Y488195D01*
X294476Y486358D01*
X295882Y484951D01*
X297720Y484190D01*
X299709D01*
X301547Y484951D01*
X302954Y486358D01*
X303715Y488195D01*
Y490185D01*
X302954Y492022D01*
X301547Y493429D01*
X299709Y494190D01*
D02*
G37*
G36*
X352495Y493750D02*
X350505D01*
X348668Y492989D01*
X347261Y491582D01*
X346500Y489745D01*
Y487755D01*
X347261Y485918D01*
X348668Y484511D01*
X350505Y483750D01*
X352495D01*
X354332Y484511D01*
X355739Y485918D01*
X356500Y487755D01*
Y489745D01*
X355739Y491582D01*
X354332Y492989D01*
X352495Y493750D01*
D02*
G37*
G36*
X295495Y459750D02*
X293505D01*
X291668Y458989D01*
X290261Y457582D01*
X289500Y455745D01*
Y453755D01*
X290261Y451918D01*
X291668Y450511D01*
X293505Y449750D01*
X295495D01*
X297332Y450511D01*
X298739Y451918D01*
X299500Y453755D01*
Y455745D01*
X298739Y457582D01*
X297332Y458989D01*
X295495Y459750D01*
D02*
G37*
G36*
X364495Y454682D02*
X362505D01*
X360668Y453921D01*
X359261Y452514D01*
X358500Y450676D01*
Y448687D01*
X359261Y446849D01*
X360668Y445443D01*
X362505Y444682D01*
X364495D01*
X366332Y445443D01*
X367739Y446849D01*
X368500Y448687D01*
Y450676D01*
X367739Y452514D01*
X366332Y453921D01*
X364495Y454682D01*
D02*
G37*
G36*
X52639Y469450D02*
X49361D01*
X46195Y468602D01*
X43355Y466963D01*
X41038Y464645D01*
X39398Y461805D01*
X38550Y458639D01*
Y455361D01*
X39398Y452195D01*
X41038Y449356D01*
X43355Y447038D01*
X46195Y445398D01*
X49361Y444550D01*
X52639D01*
X55806Y445398D01*
X58644Y447038D01*
X60963Y449356D01*
X62602Y452195D01*
X63450Y455361D01*
Y458639D01*
X62602Y461805D01*
X60963Y464645D01*
X58644Y466963D01*
X55806Y468602D01*
X52639Y469450D01*
D02*
G37*
G36*
X446108Y477750D02*
X444118D01*
X442281Y476989D01*
X440874Y475582D01*
X440113Y473745D01*
Y471755D01*
X440874Y469918D01*
X442281Y468511D01*
X444118Y467750D01*
X444236D01*
X444753Y466480D01*
X443308Y464318D01*
X442144Y461507D01*
X441550Y458522D01*
Y455478D01*
X442144Y452493D01*
X443308Y449682D01*
X444999Y447151D01*
X447151Y444999D01*
X449682Y443308D01*
X452493Y442144D01*
X455478Y441550D01*
X458522D01*
X461507Y442144D01*
X464318Y443308D01*
X466849Y444999D01*
X468730Y446880D01*
X469393Y446815D01*
X469759Y446711D01*
X470101Y446512D01*
X470761Y444918D01*
X472168Y443511D01*
X474005Y442750D01*
X475995D01*
X477832Y443511D01*
X479239Y444918D01*
X480000Y446755D01*
Y448745D01*
X479239Y450582D01*
X477832Y451989D01*
X475995Y452750D01*
X474005D01*
X473130Y452387D01*
X472017Y453301D01*
X472450Y455478D01*
Y458522D01*
X471856Y461507D01*
X470692Y464318D01*
X469001Y466849D01*
X466849Y469001D01*
X464318Y470692D01*
X461507Y471856D01*
X458522Y472450D01*
X455478D01*
X452493Y471856D01*
X451286Y471356D01*
X451080Y471427D01*
X450113Y472245D01*
Y473745D01*
X449352Y475582D01*
X447945Y476989D01*
X446108Y477750D01*
D02*
G37*
G36*
X286245Y451030D02*
X284255D01*
X282418Y450269D01*
X281011Y448862D01*
X280250Y447025D01*
Y445035D01*
X281011Y443198D01*
X282418Y441791D01*
X284255Y441030D01*
X286245D01*
X288082Y441791D01*
X289489Y443198D01*
X290250Y445035D01*
Y447025D01*
X289489Y448862D01*
X288082Y450269D01*
X286245Y451030D01*
D02*
G37*
G36*
X373495Y445000D02*
X371505D01*
X369668Y444239D01*
X368261Y442832D01*
X367500Y440995D01*
Y439005D01*
X368261Y437168D01*
X369668Y435761D01*
X371505Y435000D01*
X373495D01*
X375332Y435761D01*
X376739Y437168D01*
X377500Y439005D01*
Y440995D01*
X376739Y442832D01*
X375332Y444239D01*
X373495Y445000D01*
D02*
G37*
G36*
X271915Y442500D02*
X269926D01*
X268088Y441739D01*
X266682Y440332D01*
X265921Y438495D01*
Y436505D01*
X266682Y434668D01*
X268088Y433261D01*
X269926Y432500D01*
X271915D01*
X273753Y433261D01*
X275159Y434668D01*
X275921Y436505D01*
Y438495D01*
X275159Y440332D01*
X273753Y441739D01*
X271915Y442500D01*
D02*
G37*
G36*
X415019Y472500D02*
X410981D01*
X407020Y471712D01*
X403290Y470167D01*
X399932Y467923D01*
X397077Y465068D01*
X394833Y461710D01*
X393288Y457980D01*
X392500Y454019D01*
Y449981D01*
X393288Y446020D01*
X394833Y442290D01*
X397077Y438932D01*
X399932Y436077D01*
X403290Y433833D01*
X407020Y432288D01*
X410981Y431500D01*
X415019D01*
X418980Y432288D01*
X422710Y433833D01*
X426068Y436077D01*
X428923Y438932D01*
X431167Y442290D01*
X432712Y446020D01*
X433500Y449981D01*
Y454019D01*
X432712Y457980D01*
X431167Y461710D01*
X428923Y465068D01*
X426068Y467923D01*
X422710Y470167D01*
X418980Y471712D01*
X415019Y472500D01*
D02*
G37*
G36*
X208700Y437800D02*
X206711D01*
X204874Y437039D01*
X203467Y435632D01*
X202706Y433794D01*
Y431805D01*
X203467Y429967D01*
X204874Y428561D01*
X206711Y427800D01*
X208700D01*
X210538Y428561D01*
X211945Y429967D01*
X212706Y431805D01*
Y433794D01*
X211945Y435632D01*
X210538Y437039D01*
X208700Y437800D01*
D02*
G37*
G36*
X176745D02*
X174755D01*
X172918Y437039D01*
X171511Y435632D01*
X170750Y433794D01*
Y431805D01*
X171511Y429967D01*
X172918Y428561D01*
X174755Y427800D01*
X176745D01*
X178582Y428561D01*
X179989Y429967D01*
X180750Y431805D01*
Y433794D01*
X179989Y435632D01*
X178582Y437039D01*
X176745Y437800D01*
D02*
G37*
G36*
X235392Y427690D02*
X233403D01*
X231566Y426929D01*
X230159Y425522D01*
X229398Y423685D01*
Y421696D01*
X230159Y419858D01*
X231566Y418451D01*
X233403Y417690D01*
X235392D01*
X237230Y418451D01*
X238637Y419858D01*
X239398Y421696D01*
Y423685D01*
X238637Y425522D01*
X237230Y426929D01*
X235392Y427690D01*
D02*
G37*
G36*
X97019Y457500D02*
X92981D01*
X89020Y456712D01*
X85289Y455167D01*
X81932Y452923D01*
X79077Y450068D01*
X76833Y446710D01*
X75288Y442980D01*
X74500Y439019D01*
Y434981D01*
X75288Y431020D01*
X76833Y427290D01*
X79077Y423932D01*
X81932Y421077D01*
X85289Y418833D01*
X89020Y417288D01*
X92981Y416500D01*
X97019D01*
X100980Y417288D01*
X104710Y418833D01*
X108068Y421077D01*
X110923Y423932D01*
X113167Y427290D01*
X114712Y431020D01*
X115500Y434981D01*
Y439019D01*
X114712Y442980D01*
X113167Y446710D01*
X110923Y450068D01*
X108068Y452923D01*
X104710Y455167D01*
X100980Y456712D01*
X97019Y457500D01*
D02*
G37*
G36*
X445994Y426418D02*
X444005D01*
X442167Y425657D01*
X440760Y424250D01*
X439999Y422412D01*
Y420423D01*
X440760Y418585D01*
X442167Y417179D01*
X444005Y416418D01*
X445994D01*
X447831Y417179D01*
X449238Y418585D01*
X449999Y420423D01*
Y422412D01*
X449238Y424250D01*
X447831Y425657D01*
X445994Y426418D01*
D02*
G37*
G36*
X224367Y420288D02*
X222378D01*
X220540Y419527D01*
X219134Y418120D01*
X218373Y416283D01*
Y414294D01*
X219134Y412456D01*
X220540Y411049D01*
X222378Y410288D01*
X224367D01*
X226205Y411049D01*
X227611Y412456D01*
X228373Y414294D01*
Y416283D01*
X227611Y418120D01*
X226205Y419527D01*
X224367Y420288D01*
D02*
G37*
G36*
X343698Y411495D02*
X341709D01*
X339871Y410734D01*
X338465Y409328D01*
X337703Y407490D01*
Y405501D01*
X338465Y403663D01*
X339871Y402257D01*
X341709Y401495D01*
X343698D01*
X345536Y402257D01*
X346942Y403663D01*
X347703Y405501D01*
Y407490D01*
X346942Y409328D01*
X345536Y410734D01*
X343698Y411495D01*
D02*
G37*
G36*
X207950Y402805D02*
X205961D01*
X204124Y402044D01*
X202717Y400638D01*
X201956Y398800D01*
Y396811D01*
X202717Y394973D01*
X204124Y393567D01*
X205961Y392805D01*
X207950D01*
X209788Y393567D01*
X211195Y394973D01*
X211956Y396811D01*
Y398800D01*
X211195Y400638D01*
X209788Y402044D01*
X207950Y402805D01*
D02*
G37*
G36*
X332495Y405274D02*
X330505D01*
X328668Y404513D01*
X327261Y403106D01*
X326500Y401268D01*
Y399279D01*
X326657Y398900D01*
X326005Y397924D01*
X324168Y397163D01*
X322761Y395757D01*
X322000Y393919D01*
Y391930D01*
X322761Y390092D01*
X324168Y388686D01*
X326005Y387924D01*
X327995D01*
X329832Y388686D01*
X331239Y390092D01*
X332000Y391930D01*
Y393919D01*
X331843Y394298D01*
X332495Y395274D01*
X334332Y396035D01*
X335739Y397442D01*
X336500Y399279D01*
Y401268D01*
X335739Y403106D01*
X334332Y404513D01*
X332495Y405274D01*
D02*
G37*
G36*
X52495Y395689D02*
X50505D01*
X48668Y394928D01*
X47261Y393521D01*
X46500Y391684D01*
Y389695D01*
X47261Y387857D01*
X48668Y386450D01*
X50505Y385689D01*
X52495D01*
X54332Y386450D01*
X55739Y387857D01*
X56500Y389695D01*
Y391684D01*
X55739Y393521D01*
X54332Y394928D01*
X52495Y395689D01*
D02*
G37*
G36*
X364278Y394088D02*
X362289D01*
X360452Y393327D01*
X359045Y391920D01*
X358284Y390083D01*
Y388093D01*
X359045Y386256D01*
X360452Y384849D01*
X362289Y384088D01*
X364278D01*
X366116Y384849D01*
X367523Y386256D01*
X368284Y388093D01*
Y390083D01*
X367523Y391920D01*
X366116Y393327D01*
X364278Y394088D01*
D02*
G37*
G36*
X298245Y390500D02*
X296255D01*
X294418Y389739D01*
X293011Y388332D01*
X292250Y386495D01*
Y384505D01*
X293011Y382668D01*
X294418Y381261D01*
X296255Y380500D01*
X298245D01*
X300082Y381261D01*
X301489Y382668D01*
X302250Y384505D01*
Y386495D01*
X301489Y388332D01*
X300082Y389739D01*
X298245Y390500D01*
D02*
G37*
G36*
X18495Y393019D02*
X16505D01*
X14668Y392258D01*
X13261Y390851D01*
X12500Y389014D01*
Y387025D01*
X13261Y385187D01*
X14668Y383780D01*
X15219Y383552D01*
Y382177D01*
X14668Y381949D01*
X13261Y380542D01*
X12500Y378705D01*
Y376715D01*
X13261Y374878D01*
X14668Y373471D01*
X16505Y372710D01*
X18495D01*
X20332Y373471D01*
X21739Y374878D01*
X22500Y376715D01*
Y378705D01*
X21739Y380542D01*
X20332Y381949D01*
X19781Y382177D01*
Y383552D01*
X20332Y383780D01*
X21739Y385187D01*
X22500Y387025D01*
Y389014D01*
X21739Y390851D01*
X20332Y392258D01*
X18495Y393019D01*
D02*
G37*
G36*
X110245Y382668D02*
X108255D01*
X106418Y381907D01*
X105011Y380501D01*
X104250Y378663D01*
Y376674D01*
X105011Y374836D01*
X106418Y373430D01*
X108255Y372668D01*
X110245D01*
X112082Y373430D01*
X113489Y374836D01*
X114250Y376674D01*
Y378663D01*
X113489Y380501D01*
X112082Y381907D01*
X110245Y382668D01*
D02*
G37*
G36*
X265495Y380775D02*
X263505D01*
X261668Y380014D01*
X260261Y378608D01*
X259500Y376770D01*
Y374781D01*
X260261Y372943D01*
X261668Y371536D01*
X263505Y370775D01*
X265495D01*
X267332Y371536D01*
X268739Y372943D01*
X269500Y374781D01*
Y376770D01*
X268739Y378608D01*
X267332Y380014D01*
X265495Y380775D01*
D02*
G37*
G36*
X441346Y379949D02*
X439357D01*
X437519Y379188D01*
X436113Y377782D01*
X435352Y375944D01*
Y373955D01*
X436113Y372117D01*
X437519Y370711D01*
X439357Y369949D01*
X441346D01*
X443184Y370711D01*
X444590Y372117D01*
X445352Y373955D01*
Y375944D01*
X444590Y377782D01*
X443184Y379188D01*
X441346Y379949D01*
D02*
G37*
G36*
X344671Y365775D02*
X342682D01*
X340844Y365014D01*
X339438Y363608D01*
X338677Y361770D01*
Y359781D01*
X339438Y357943D01*
X340844Y356536D01*
X342682Y355775D01*
X344671D01*
X346509Y356536D01*
X347915Y357943D01*
X348676Y359781D01*
Y361770D01*
X347915Y363608D01*
X346509Y365014D01*
X344671Y365775D01*
D02*
G37*
G36*
X142995Y364750D02*
X141005D01*
X139168Y363989D01*
X137761Y362582D01*
X137000Y360745D01*
Y358755D01*
X137761Y356918D01*
X139168Y355511D01*
X141005Y354750D01*
X142995D01*
X144832Y355511D01*
X146239Y356918D01*
X147000Y358755D01*
Y360745D01*
X146239Y362582D01*
X144832Y363989D01*
X142995Y364750D01*
D02*
G37*
G36*
X104745Y363378D02*
X102755D01*
X100918Y362617D01*
X99511Y361210D01*
X98750Y359372D01*
Y357383D01*
X99511Y355545D01*
X100918Y354139D01*
X102755Y353378D01*
X104745D01*
X106582Y354139D01*
X107989Y355545D01*
X108750Y357383D01*
Y359372D01*
X107989Y361210D01*
X106582Y362617D01*
X104745Y363378D01*
D02*
G37*
G36*
X56961Y359628D02*
X54972D01*
X53135Y358867D01*
X51728Y357460D01*
X50967Y355622D01*
Y353633D01*
X51728Y351795D01*
X53135Y350389D01*
X54972Y349628D01*
X56961D01*
X58799Y350389D01*
X60206Y351795D01*
X60967Y353633D01*
Y355622D01*
X60206Y357460D01*
X58799Y358867D01*
X56961Y359628D01*
D02*
G37*
G36*
X260487Y358693D02*
X258498D01*
X256660Y357932D01*
X255254Y356526D01*
X254492Y354688D01*
Y352699D01*
X255254Y350861D01*
X256660Y349454D01*
X258498Y348693D01*
X260487D01*
X262325Y349454D01*
X263731Y350861D01*
X264492Y352699D01*
Y354688D01*
X263731Y356526D01*
X262325Y357932D01*
X260487Y358693D01*
D02*
G37*
G36*
X275408Y357344D02*
X273419D01*
X271581Y356583D01*
X270175Y355176D01*
X269414Y353338D01*
Y351349D01*
X270175Y349512D01*
X271581Y348105D01*
X273419Y347344D01*
X275408D01*
X277246Y348105D01*
X278653Y349512D01*
X279414Y351349D01*
Y353338D01*
X278653Y355176D01*
X277246Y356583D01*
X275408Y357344D01*
D02*
G37*
G36*
X18456Y352587D02*
X16467D01*
X14629Y351826D01*
X13223Y350419D01*
X12462Y348582D01*
Y346593D01*
X13223Y344755D01*
X14629Y343348D01*
X16467Y342587D01*
X18456D01*
X20294Y343348D01*
X21701Y344755D01*
X22462Y346593D01*
Y348582D01*
X21701Y350419D01*
X20294Y351826D01*
X18456Y352587D01*
D02*
G37*
G36*
X207536Y337843D02*
X205547D01*
X203710Y337082D01*
X202303Y335676D01*
X201542Y333838D01*
Y331849D01*
X202303Y330011D01*
X203710Y328605D01*
X205547Y327843D01*
X207536D01*
X209374Y328605D01*
X210781Y330011D01*
X211542Y331849D01*
Y333838D01*
X210781Y335676D01*
X209374Y337082D01*
X207536Y337843D01*
D02*
G37*
G36*
X194286Y335805D02*
X192297D01*
X190460Y335044D01*
X189053Y333638D01*
X188292Y331800D01*
Y329811D01*
X189053Y327973D01*
X190460Y326567D01*
X192297Y325805D01*
X194286D01*
X196124Y326567D01*
X197531Y327973D01*
X198292Y329811D01*
Y331800D01*
X197531Y333638D01*
X196124Y335044D01*
X194286Y335805D01*
D02*
G37*
G36*
X335745Y331000D02*
X333755D01*
X331918Y330239D01*
X330511Y328832D01*
X329750Y326995D01*
Y325005D01*
X330511Y323168D01*
X331918Y321761D01*
X333755Y321000D01*
X335745D01*
X337582Y321761D01*
X338989Y323168D01*
X339750Y325005D01*
Y326995D01*
X338989Y328832D01*
X337582Y330239D01*
X335745Y331000D01*
D02*
G37*
G36*
X467243Y377500D02*
X462757D01*
X458326Y376798D01*
X454060Y375412D01*
X450063Y373375D01*
X446433Y370739D01*
X443261Y367566D01*
X440625Y363937D01*
X438588Y359940D01*
X437202Y355674D01*
X436500Y351243D01*
Y346757D01*
X437202Y342326D01*
X438588Y338060D01*
X440625Y334063D01*
X443261Y330434D01*
X446433Y327261D01*
X450063Y324625D01*
X454060Y322588D01*
X458326Y321202D01*
X462757Y320500D01*
X467243D01*
X471674Y321202D01*
X475940Y322588D01*
X479937Y324625D01*
X483567Y327261D01*
X486739Y330434D01*
X489375Y334063D01*
X491412Y338060D01*
X492798Y342326D01*
X493500Y346757D01*
Y351243D01*
X492798Y355674D01*
X491412Y359940D01*
X489375Y363937D01*
X486739Y367566D01*
X483567Y370739D01*
X479937Y373375D01*
X475940Y375412D01*
X471674Y376798D01*
X467243Y377500D01*
D02*
G37*
G36*
X376745Y327588D02*
X374755D01*
X372918Y326827D01*
X371511Y325420D01*
X370750Y323583D01*
Y321593D01*
X371511Y319756D01*
X372918Y318349D01*
X374755Y317588D01*
X376745D01*
X378582Y318349D01*
X379989Y319756D01*
X380750Y321593D01*
Y323583D01*
X379989Y325420D01*
X378582Y326827D01*
X376745Y327588D01*
D02*
G37*
G36*
X268756Y324250D02*
X266767D01*
X264929Y323489D01*
X263522Y322082D01*
X262761Y320245D01*
Y318256D01*
X263522Y316418D01*
X264929Y315011D01*
X266767Y314250D01*
X268756D01*
X270593Y315011D01*
X272000Y316418D01*
X272761Y318256D01*
Y320245D01*
X272000Y322082D01*
X270593Y323489D01*
X268756Y324250D01*
D02*
G37*
G36*
X242192Y313750D02*
X240203D01*
X238365Y312989D01*
X236958Y311582D01*
X236197Y309745D01*
Y307755D01*
X236958Y305918D01*
X238365Y304511D01*
X240203Y303750D01*
X242192D01*
X244029Y304511D01*
X245436Y305918D01*
X246197Y307755D01*
Y309745D01*
X245436Y311582D01*
X244029Y312989D01*
X242192Y313750D01*
D02*
G37*
G36*
X364957Y302432D02*
X362967D01*
X361130Y301671D01*
X359723Y300264D01*
X358962Y298427D01*
Y296438D01*
X359723Y294600D01*
X361130Y293193D01*
X362967Y292432D01*
X364957D01*
X366794Y293193D01*
X368201Y294600D01*
X368962Y296438D01*
Y298427D01*
X368201Y300264D01*
X366794Y301671D01*
X364957Y302432D01*
D02*
G37*
G36*
X273887Y299750D02*
X271897D01*
X270060Y298989D01*
X268653Y297582D01*
X267892Y295745D01*
Y293755D01*
X268653Y291918D01*
X270060Y290511D01*
X271897Y289750D01*
X273887D01*
X275724Y290511D01*
X277131Y291918D01*
X277892Y293755D01*
Y295745D01*
X277131Y297582D01*
X275724Y298989D01*
X273887Y299750D01*
D02*
G37*
G36*
X258995Y297250D02*
X257005D01*
X255168Y296489D01*
X253761Y295082D01*
X253000Y293245D01*
Y291255D01*
X253761Y289418D01*
X255168Y288011D01*
X257005Y287250D01*
X258995D01*
X260832Y288011D01*
X262239Y289418D01*
X263000Y291255D01*
Y293245D01*
X262239Y295082D01*
X260832Y296489D01*
X258995Y297250D01*
D02*
G37*
G36*
X233244Y296385D02*
X231255D01*
X229418Y295624D01*
X228011Y294217D01*
X227250Y292380D01*
Y290391D01*
X228011Y288553D01*
X229418Y287146D01*
X231255Y286385D01*
X233244D01*
X235082Y287146D01*
X236489Y288553D01*
X237250Y290391D01*
Y292380D01*
X236489Y294217D01*
X235082Y295624D01*
X233244Y296385D01*
D02*
G37*
G36*
X157747Y281869D02*
X155758D01*
X153920Y281108D01*
X152514Y279701D01*
X151752Y277864D01*
Y275875D01*
X152514Y274037D01*
X153920Y272630D01*
X155758Y271869D01*
X157747D01*
X159585Y272630D01*
X160991Y274037D01*
X161752Y275875D01*
Y277864D01*
X160991Y279701D01*
X159585Y281108D01*
X157747Y281869D01*
D02*
G37*
G36*
X404053Y282430D02*
X401947D01*
X399912Y281885D01*
X398088Y280832D01*
X396599Y279343D01*
X395545Y277518D01*
X395000Y275484D01*
Y273377D01*
X395545Y271343D01*
X396599Y269518D01*
X398088Y268029D01*
X398687Y267683D01*
X398853Y266424D01*
X398761Y266332D01*
X398000Y264495D01*
Y262505D01*
X398761Y260668D01*
X400168Y259261D01*
X402005Y258500D01*
X403995D01*
X405832Y259261D01*
X407239Y260668D01*
X408000Y262505D01*
Y264495D01*
X407239Y266332D01*
X407147Y266424D01*
X407313Y267683D01*
X407912Y268029D01*
X409402Y269518D01*
X409814Y270232D01*
X411401Y270441D01*
X411650Y270192D01*
X413488Y269431D01*
X415477D01*
X417314Y270192D01*
X418721Y271598D01*
X419482Y273436D01*
Y275425D01*
X418721Y277263D01*
X417314Y278669D01*
X415477Y279431D01*
X413488D01*
X411650Y278669D01*
X411401Y278420D01*
X409814Y278629D01*
X409402Y279343D01*
X407912Y280832D01*
X406088Y281885D01*
X404053Y282430D01*
D02*
G37*
G36*
X290245Y274500D02*
X288255D01*
X286418Y273739D01*
X285011Y272332D01*
X284250Y270495D01*
Y268505D01*
X285011Y266668D01*
X286418Y265261D01*
X288255Y264500D01*
X290245D01*
X292082Y265261D01*
X293489Y266668D01*
X294250Y268505D01*
Y270495D01*
X293489Y272332D01*
X292082Y273739D01*
X290245Y274500D01*
D02*
G37*
G36*
X145995Y269000D02*
X144005D01*
X142168Y268239D01*
X140761Y266832D01*
X140000Y264995D01*
Y263005D01*
X140761Y261168D01*
X142168Y259761D01*
X144005Y259000D01*
X145995D01*
X147832Y259761D01*
X149239Y261168D01*
X150000Y263005D01*
Y264995D01*
X149239Y266832D01*
X147832Y268239D01*
X145995Y269000D01*
D02*
G37*
G36*
X53103Y259060D02*
X51114D01*
X49276Y258298D01*
X47869Y256892D01*
X47108Y255054D01*
Y253065D01*
X47869Y251227D01*
X49276Y249821D01*
X51114Y249060D01*
X53103D01*
X54941Y249821D01*
X56347Y251227D01*
X57108Y253065D01*
Y255054D01*
X56347Y256892D01*
X54941Y258298D01*
X53103Y259060D01*
D02*
G37*
G36*
X84947Y267552D02*
X82957D01*
X81120Y266790D01*
X79713Y265384D01*
X78952Y263546D01*
Y261557D01*
X79713Y259719D01*
X81120Y258313D01*
X82774Y257628D01*
X82931Y256978D01*
X82900Y256305D01*
X81532Y255739D01*
X80126Y254332D01*
X79365Y252495D01*
Y250505D01*
X80126Y248668D01*
X81532Y247261D01*
X83370Y246500D01*
X85359D01*
X87197Y247261D01*
X88604Y248668D01*
X89365Y250505D01*
Y252495D01*
X88604Y254332D01*
X87197Y255739D01*
X85543Y256424D01*
X85386Y257073D01*
X85417Y257746D01*
X86784Y258313D01*
X88191Y259719D01*
X88952Y261557D01*
Y263546D01*
X88191Y265384D01*
X86784Y266790D01*
X84947Y267552D01*
D02*
G37*
G36*
X146314Y254000D02*
X144325D01*
X142487Y253239D01*
X141080Y251832D01*
X140319Y249995D01*
Y248005D01*
X141080Y246168D01*
X142487Y244761D01*
X144325Y244000D01*
X146314D01*
X148151Y244761D01*
X149558Y246168D01*
X150319Y248005D01*
Y249995D01*
X149558Y251832D01*
X148151Y253239D01*
X146314Y254000D01*
D02*
G37*
G36*
X458639Y266450D02*
X455361D01*
X452195Y265602D01*
X449356Y263962D01*
X447038Y261644D01*
X445398Y258806D01*
X444550Y255639D01*
Y252361D01*
X445398Y249195D01*
X447038Y246355D01*
X449356Y244037D01*
X452195Y242398D01*
X455361Y241550D01*
X458639D01*
X461805Y242398D01*
X464645Y244037D01*
X466963Y246355D01*
X468602Y249195D01*
X469450Y252361D01*
Y255639D01*
X468602Y258806D01*
X466963Y261644D01*
X464645Y263962D01*
X461805Y265602D01*
X458639Y266450D01*
D02*
G37*
G36*
X23696Y251500D02*
X21707D01*
X19869Y250739D01*
X18463Y249332D01*
X17702Y247495D01*
Y245505D01*
X18463Y243668D01*
X19869Y242261D01*
X21707Y241500D01*
X23696D01*
X25534Y242261D01*
X26941Y243668D01*
X27702Y245505D01*
Y247495D01*
X26941Y249332D01*
X25534Y250739D01*
X23696Y251500D01*
D02*
G37*
G36*
X294669Y249381D02*
X292679D01*
X290842Y248620D01*
X289435Y247213D01*
X288674Y245375D01*
Y243386D01*
X289435Y241549D01*
X290842Y240142D01*
X292679Y239381D01*
X294669D01*
X296506Y240142D01*
X297913Y241549D01*
X298674Y243386D01*
Y245375D01*
X297913Y247213D01*
X296506Y248620D01*
X294669Y249381D01*
D02*
G37*
G36*
X274495D02*
X272505D01*
X270668Y248620D01*
X269261Y247213D01*
X268500Y245375D01*
Y243386D01*
X269261Y241549D01*
X270668Y240142D01*
X272505Y239381D01*
X274495D01*
X276332Y240142D01*
X277739Y241549D01*
X278500Y243386D01*
Y245375D01*
X277739Y247213D01*
X276332Y248620D01*
X274495Y249381D01*
D02*
G37*
G36*
X258995D02*
X257005D01*
X255168Y248620D01*
X253761Y247213D01*
X253000Y245375D01*
Y243386D01*
X253761Y241549D01*
X255168Y240142D01*
X257005Y239381D01*
X258995D01*
X260832Y240142D01*
X262239Y241549D01*
X263000Y243386D01*
Y245375D01*
X262239Y247213D01*
X260832Y248620D01*
X258995Y249381D01*
D02*
G37*
G36*
X244495D02*
X242505D01*
X240668Y248620D01*
X239261Y247213D01*
X238500Y245375D01*
Y243386D01*
X239261Y241549D01*
X240668Y240142D01*
X242505Y239381D01*
X244495D01*
X246332Y240142D01*
X247739Y241549D01*
X248500Y243386D01*
Y245375D01*
X247739Y247213D01*
X246332Y248620D01*
X244495Y249381D01*
D02*
G37*
G36*
X345745Y248000D02*
X343755D01*
X341918Y247239D01*
X340511Y245832D01*
X339750Y243995D01*
Y242005D01*
X340511Y240168D01*
X341918Y238761D01*
X343755Y238000D01*
X345745D01*
X347582Y238761D01*
X348989Y240168D01*
X349750Y242005D01*
Y243995D01*
X348989Y245832D01*
X347582Y247239D01*
X345745Y248000D01*
D02*
G37*
G36*
X332995D02*
X331005D01*
X329168Y247239D01*
X327761Y245832D01*
X327000Y243995D01*
Y242005D01*
X327761Y240168D01*
X329168Y238761D01*
X331005Y238000D01*
X332995D01*
X334832Y238761D01*
X336239Y240168D01*
X337000Y242005D01*
Y243995D01*
X336239Y245832D01*
X334832Y247239D01*
X332995Y248000D01*
D02*
G37*
G36*
X394245Y247500D02*
X392255D01*
X390418Y246739D01*
X389011Y245332D01*
X388250Y243495D01*
Y241505D01*
X389011Y239668D01*
X390418Y238261D01*
X392255Y237500D01*
X394245D01*
X396082Y238261D01*
X397489Y239668D01*
X398250Y241505D01*
Y243495D01*
X397489Y245332D01*
X396082Y246739D01*
X394245Y247500D01*
D02*
G37*
G36*
X147745Y235310D02*
X145756D01*
X143918Y234549D01*
X142511Y233142D01*
X141750Y231305D01*
Y229315D01*
X142511Y227478D01*
X143918Y226071D01*
X145756Y225310D01*
X147745D01*
X149582Y226071D01*
X150989Y227478D01*
X151750Y229315D01*
Y231305D01*
X150989Y233142D01*
X149582Y234549D01*
X147745Y235310D01*
D02*
G37*
G36*
X67653Y229000D02*
X65664D01*
X63826Y228239D01*
X62420Y226832D01*
X61659Y224995D01*
Y223005D01*
X62420Y221168D01*
X62640Y220948D01*
X62567Y219519D01*
X61380Y218332D01*
X60619Y216495D01*
Y214505D01*
X61380Y212668D01*
X62786Y211261D01*
X64624Y210500D01*
X66613D01*
X68451Y211261D01*
X69858Y212668D01*
X70619Y214505D01*
Y216495D01*
X69858Y218332D01*
X69638Y218552D01*
X69711Y219981D01*
X70898Y221168D01*
X71659Y223005D01*
Y224995D01*
X70898Y226832D01*
X69491Y228239D01*
X67653Y229000D01*
D02*
G37*
G36*
X351245Y216521D02*
X349255D01*
X347418Y215760D01*
X346011Y214353D01*
X345250Y212516D01*
Y210526D01*
X346011Y208689D01*
X347418Y207282D01*
X349255Y206521D01*
X351245D01*
X353082Y207282D01*
X354489Y208689D01*
X355250Y210526D01*
Y212516D01*
X354489Y214353D01*
X353082Y215760D01*
X351245Y216521D01*
D02*
G37*
G36*
X259933Y214744D02*
X257944D01*
X256106Y213983D01*
X254700Y212576D01*
X253939Y210738D01*
Y208749D01*
X254700Y206912D01*
X256106Y205505D01*
X257944Y204744D01*
X259933D01*
X261771Y205505D01*
X263178Y206912D01*
X263939Y208749D01*
Y210738D01*
X263178Y212576D01*
X261771Y213983D01*
X259933Y214744D01*
D02*
G37*
G36*
X244933D02*
X242944D01*
X241106Y213983D01*
X239700Y212576D01*
X238939Y210738D01*
Y208749D01*
X239700Y206912D01*
X241106Y205505D01*
X242944Y204744D01*
X244933D01*
X246771Y205505D01*
X248178Y206912D01*
X248939Y208749D01*
Y210738D01*
X248178Y212576D01*
X246771Y213983D01*
X244933Y214744D01*
D02*
G37*
G36*
X66468Y203873D02*
X64479D01*
X62641Y203112D01*
X61234Y201705D01*
X60473Y199867D01*
Y197878D01*
X61234Y196041D01*
X62641Y194634D01*
X64479Y193873D01*
X66468D01*
X68305Y194634D01*
X69712Y196041D01*
X70473Y197878D01*
Y199867D01*
X69712Y201705D01*
X68305Y203112D01*
X66468Y203873D01*
D02*
G37*
G36*
X53113Y202290D02*
X51124D01*
X49286Y201529D01*
X47880Y200123D01*
X47118Y198285D01*
Y196296D01*
X47880Y194458D01*
X49286Y193052D01*
X51124Y192290D01*
X53113D01*
X54951Y193052D01*
X56357Y194458D01*
X57118Y196296D01*
Y198285D01*
X56357Y200123D01*
X54951Y201529D01*
X53113Y202290D01*
D02*
G37*
G36*
X404053Y193091D02*
X401947D01*
X399912Y192545D01*
X398088Y191492D01*
X396599Y190003D01*
X396073Y189092D01*
X394814Y188927D01*
X394411Y189329D01*
X392573Y190091D01*
X390584D01*
X388746Y189329D01*
X387340Y187923D01*
X386579Y186085D01*
Y184096D01*
X387340Y182258D01*
X388746Y180852D01*
X390584Y180091D01*
X392573D01*
X394411Y180852D01*
X394814Y181255D01*
X396073Y181089D01*
X396599Y180179D01*
X398088Y178689D01*
X398947Y178193D01*
X399113Y176934D01*
X398761Y176582D01*
X398000Y174745D01*
Y172755D01*
X398761Y170918D01*
X400168Y169511D01*
X402005Y168750D01*
X403995D01*
X405832Y169511D01*
X407239Y170918D01*
X408000Y172755D01*
Y174745D01*
X407239Y176582D01*
X406887Y176934D01*
X407053Y178193D01*
X407912Y178689D01*
X409402Y180179D01*
X410455Y182003D01*
X411000Y184037D01*
Y186144D01*
X410455Y188179D01*
X409402Y190003D01*
X407912Y191492D01*
X406088Y192545D01*
X404053Y193091D01*
D02*
G37*
G36*
X271183Y192644D02*
X269194D01*
X267356Y191882D01*
X265950Y190476D01*
X265189Y188638D01*
Y186649D01*
X265950Y184811D01*
X267356Y183405D01*
X269194Y182644D01*
X271183D01*
X273021Y183405D01*
X274428Y184811D01*
X275189Y186649D01*
Y188638D01*
X274428Y190476D01*
X273021Y191882D01*
X271183Y192644D01*
D02*
G37*
G36*
X61243Y191100D02*
X58057D01*
X54980Y190275D01*
X52220Y188682D01*
X49967Y186430D01*
X48375Y183670D01*
X47620Y180854D01*
X46350Y181021D01*
Y191100D01*
X22150D01*
Y166900D01*
X46350D01*
Y176978D01*
X47620Y177146D01*
X48375Y174330D01*
X49967Y171570D01*
X52220Y169318D01*
X54980Y167725D01*
X58057Y166900D01*
X61243D01*
X62285Y167179D01*
X62942Y166040D01*
X62261Y165360D01*
X61500Y163522D01*
Y161533D01*
X62261Y159695D01*
X63668Y158288D01*
X65505Y157527D01*
X67495D01*
X69332Y158288D01*
X70739Y159695D01*
X71500Y161533D01*
X72704D01*
X73465Y159695D01*
X74872Y158288D01*
X76710Y157527D01*
X78699D01*
X80536Y158288D01*
X81943Y159695D01*
X82704Y161533D01*
Y163522D01*
X81943Y165360D01*
X80536Y166766D01*
X78699Y167527D01*
X76710D01*
X74872Y166766D01*
X73465Y165360D01*
X72704Y163522D01*
X71500D01*
X70739Y165360D01*
X69332Y166766D01*
X67495Y167527D01*
X66519D01*
X66178Y168797D01*
X67080Y169318D01*
X69332Y171570D01*
X70925Y174330D01*
X71750Y177407D01*
Y180593D01*
X70925Y183670D01*
X69332Y186430D01*
X67080Y188682D01*
X64320Y190275D01*
X61243Y191100D01*
D02*
G37*
G36*
X244933Y187955D02*
X242944D01*
X241106Y187194D01*
X239700Y185787D01*
X238939Y183950D01*
Y181961D01*
X239700Y180123D01*
X241106Y178716D01*
X242944Y177955D01*
X244933D01*
X246771Y178716D01*
X248178Y180123D01*
X248939Y181961D01*
Y183950D01*
X248178Y185787D01*
X246771Y187194D01*
X244933Y187955D01*
D02*
G37*
G36*
X259933Y187705D02*
X257944D01*
X256106Y186944D01*
X254700Y185537D01*
X253939Y183700D01*
Y181710D01*
X254700Y179873D01*
X256106Y178466D01*
X257944Y177705D01*
X259933D01*
X261771Y178466D01*
X263178Y179873D01*
X263939Y181710D01*
Y183700D01*
X263178Y185537D01*
X261771Y186944D01*
X259933Y187705D01*
D02*
G37*
G36*
X131423Y186250D02*
X129434D01*
X127597Y185489D01*
X126190Y184082D01*
X125429Y182245D01*
Y180255D01*
X126190Y178418D01*
X127597Y177011D01*
X129434Y176250D01*
X131423D01*
X133261Y177011D01*
X134668Y178418D01*
X135429Y180255D01*
Y182245D01*
X134668Y184082D01*
X133261Y185489D01*
X131423Y186250D01*
D02*
G37*
G36*
X142995Y183086D02*
X141005D01*
X139168Y182325D01*
X137761Y180918D01*
X137000Y179081D01*
Y177092D01*
X137761Y175254D01*
X139168Y173847D01*
X141005Y173086D01*
X142995D01*
X144832Y173847D01*
X146239Y175254D01*
X147000Y177092D01*
Y179081D01*
X146239Y180918D01*
X144832Y182325D01*
X142995Y183086D01*
D02*
G37*
G36*
X160995Y191500D02*
X159005D01*
X157168Y190739D01*
X155761Y189332D01*
X155000Y187495D01*
Y185505D01*
X155761Y183668D01*
X156331Y183098D01*
X156918Y182026D01*
X155511Y180620D01*
X154750Y178782D01*
Y176793D01*
X155511Y174955D01*
X156918Y173549D01*
X158755Y172787D01*
X160745D01*
X162582Y173549D01*
X163989Y174955D01*
X164750Y176793D01*
Y178782D01*
X163989Y180620D01*
X163419Y181189D01*
X162832Y182261D01*
X164239Y183668D01*
X165000Y185505D01*
Y187495D01*
X164239Y189332D01*
X162832Y190739D01*
X160995Y191500D01*
D02*
G37*
G36*
X185402Y178689D02*
X183413D01*
X181575Y177928D01*
X180168Y176521D01*
X179407Y174684D01*
Y172695D01*
X180168Y170857D01*
X181575Y169450D01*
X183413Y168689D01*
X185402D01*
X187239Y169450D01*
X188646Y170857D01*
X189407Y172695D01*
Y174684D01*
X188646Y176521D01*
X187239Y177928D01*
X185402Y178689D01*
D02*
G37*
G36*
X172395Y178000D02*
X170406D01*
X168568Y177239D01*
X167161Y175832D01*
X166400Y173995D01*
Y172005D01*
X167161Y170168D01*
X168568Y168761D01*
X170406Y168000D01*
X172395D01*
X174232Y168761D01*
X175639Y170168D01*
X176400Y172005D01*
Y173995D01*
X175639Y175832D01*
X174232Y177239D01*
X172395Y178000D01*
D02*
G37*
G36*
X116245Y167527D02*
X114255D01*
X112418Y166766D01*
X111011Y165360D01*
X110250Y163522D01*
Y161533D01*
X111011Y159695D01*
X112418Y158288D01*
X114255Y157527D01*
X116245D01*
X118082Y158288D01*
X119489Y159695D01*
X120250Y161533D01*
Y163522D01*
X119489Y165360D01*
X118082Y166766D01*
X116245Y167527D01*
D02*
G37*
G36*
X103722D02*
X101733D01*
X99895Y166766D01*
X98489Y165360D01*
X97727Y163522D01*
Y161533D01*
X98489Y159695D01*
X99895Y158288D01*
X101733Y157527D01*
X103722D01*
X105560Y158288D01*
X106966Y159695D01*
X107727Y161533D01*
Y163522D01*
X106966Y165360D01*
X105560Y166766D01*
X103722Y167527D01*
D02*
G37*
G36*
X172995Y152750D02*
X171005D01*
X169168Y151989D01*
X167761Y150582D01*
X167000Y148745D01*
Y146755D01*
X167761Y144918D01*
X169168Y143511D01*
X171005Y142750D01*
X172995D01*
X174832Y143511D01*
X176239Y144918D01*
X177000Y146755D01*
Y148745D01*
X176239Y150582D01*
X174832Y151989D01*
X172995Y152750D01*
D02*
G37*
G36*
X159745Y137850D02*
X157755D01*
X155918Y137089D01*
X154511Y135682D01*
X153750Y133844D01*
Y131855D01*
X154511Y130018D01*
X155918Y128611D01*
X157755Y127850D01*
X159745D01*
X161582Y128611D01*
X162989Y130018D01*
X163750Y131855D01*
Y133844D01*
X162989Y135682D01*
X161582Y137089D01*
X159745Y137850D01*
D02*
G37*
G36*
X467243Y166500D02*
X462757D01*
X458326Y165798D01*
X454060Y164412D01*
X450063Y162375D01*
X446433Y159739D01*
X443261Y156566D01*
X440625Y152937D01*
X438588Y148940D01*
X437202Y144674D01*
X436500Y140243D01*
Y135757D01*
X437202Y131326D01*
X438588Y127060D01*
X440625Y123063D01*
X443261Y119433D01*
X446433Y116261D01*
X450063Y113625D01*
X454060Y111588D01*
X458326Y110202D01*
X462757Y109500D01*
X467243D01*
X471674Y110202D01*
X475940Y111588D01*
X479937Y113625D01*
X483567Y116261D01*
X486739Y119433D01*
X489375Y123063D01*
X491412Y127060D01*
X492798Y131326D01*
X493500Y135757D01*
Y140243D01*
X492798Y144674D01*
X491412Y148940D01*
X489375Y152937D01*
X486739Y156566D01*
X483567Y159739D01*
X479937Y162375D01*
X475940Y164412D01*
X471674Y165798D01*
X467243Y166500D01*
D02*
G37*
G36*
X173493Y118250D02*
X171503D01*
X169666Y117489D01*
X168259Y116082D01*
X167498Y114245D01*
Y112255D01*
X168259Y110418D01*
X169666Y109011D01*
X171503Y108250D01*
X173493D01*
X175330Y109011D01*
X176737Y110418D01*
X177498Y112255D01*
Y114245D01*
X176737Y116082D01*
X175330Y117489D01*
X173493Y118250D01*
D02*
G37*
G36*
X184133Y107103D02*
X182144D01*
X180306Y106342D01*
X178900Y104935D01*
X178138Y103098D01*
Y101109D01*
X178900Y99271D01*
X180306Y97864D01*
X182144Y97103D01*
X184133D01*
X185971Y97864D01*
X187377Y99271D01*
X188138Y101109D01*
Y103098D01*
X187377Y104935D01*
X185971Y106342D01*
X184133Y107103D01*
D02*
G37*
G36*
X170155D02*
X168166D01*
X166328Y106342D01*
X164922Y104935D01*
X164161Y103098D01*
Y101109D01*
X164922Y99271D01*
X166328Y97864D01*
X168166Y97103D01*
X170155D01*
X171993Y97864D01*
X173400Y99271D01*
X174161Y101109D01*
Y103098D01*
X173400Y104935D01*
X171993Y106342D01*
X170155Y107103D01*
D02*
G37*
G36*
X193900Y74250D02*
X191911D01*
X190073Y73489D01*
X188666Y72082D01*
X188616Y71960D01*
X187259Y72003D01*
X185971Y73291D01*
X184133Y74052D01*
X182144D01*
X180306Y73291D01*
X178900Y71885D01*
X178138Y70047D01*
Y68999D01*
X176868Y68473D01*
X176082Y69259D01*
X174245Y70020D01*
X172255D01*
X170418Y69259D01*
X169011Y67853D01*
X168250Y66015D01*
Y64026D01*
X169011Y62188D01*
X170418Y60782D01*
X172255Y60020D01*
X174245D01*
X176082Y60782D01*
X177489Y62188D01*
X178250Y64026D01*
Y65074D01*
X179520Y65600D01*
X180306Y64814D01*
X182144Y64052D01*
X184133D01*
X185971Y64814D01*
X187377Y66220D01*
X187428Y66342D01*
X188785Y66300D01*
X190073Y65011D01*
X191911Y64250D01*
X193900D01*
X195738Y65011D01*
X197144Y66418D01*
X197905Y68255D01*
Y70245D01*
X197144Y72082D01*
X195738Y73489D01*
X193900Y74250D01*
D02*
G37*
G36*
X162745Y69750D02*
X160755D01*
X158918Y68989D01*
X157511Y67582D01*
X156750Y65745D01*
Y63755D01*
X157511Y61918D01*
X158918Y60511D01*
X160755Y59750D01*
X162745D01*
X164582Y60511D01*
X165989Y61918D01*
X166750Y63755D01*
Y65745D01*
X165989Y67582D01*
X164582Y68989D01*
X162745Y69750D01*
D02*
G37*
G36*
X150495Y68250D02*
X148505D01*
X146668Y67489D01*
X145261Y66082D01*
X144500Y64245D01*
Y62255D01*
X145261Y60418D01*
X146668Y59011D01*
X148505Y58250D01*
X150495D01*
X152332Y59011D01*
X153739Y60418D01*
X154500Y62255D01*
Y64245D01*
X153739Y66082D01*
X152332Y67489D01*
X150495Y68250D01*
D02*
G37*
G36*
X97019Y91500D02*
X92981D01*
X89020Y90712D01*
X85289Y89167D01*
X81932Y86923D01*
X79077Y84068D01*
X76833Y80710D01*
X75288Y76980D01*
X74500Y73019D01*
Y68981D01*
X75288Y65020D01*
X76833Y61290D01*
X79077Y57932D01*
X81932Y55077D01*
X85289Y52833D01*
X89020Y51288D01*
X92981Y50500D01*
X97019D01*
X100980Y51288D01*
X104710Y52833D01*
X108068Y55077D01*
X110923Y57932D01*
X113167Y61290D01*
X114712Y65020D01*
X115500Y68981D01*
Y73019D01*
X114712Y76980D01*
X113167Y80710D01*
X110923Y84068D01*
X108068Y86923D01*
X104710Y89167D01*
X100980Y90712D01*
X97019Y91500D01*
D02*
G37*
G36*
X458639Y63450D02*
X455361D01*
X452195Y62602D01*
X449356Y60963D01*
X447038Y58644D01*
X445398Y55806D01*
X444550Y52639D01*
Y49361D01*
X445398Y46195D01*
X447038Y43355D01*
X449356Y41038D01*
X452195Y39398D01*
X455361Y38550D01*
X458639D01*
X461805Y39398D01*
X464645Y41038D01*
X466963Y43355D01*
X468602Y46195D01*
X469450Y49361D01*
Y52639D01*
X468602Y55806D01*
X466963Y58644D01*
X464645Y60963D01*
X461805Y62602D01*
X458639Y63450D01*
D02*
G37*
G36*
X52639D02*
X49361D01*
X46195Y62602D01*
X43355Y60963D01*
X41038Y58644D01*
X39398Y55806D01*
X38550Y52639D01*
Y49361D01*
X39398Y46195D01*
X41038Y43355D01*
X43355Y41038D01*
X46195Y39398D01*
X49361Y38550D01*
X52639D01*
X55806Y39398D01*
X58644Y41038D01*
X60963Y43355D01*
X62602Y46195D01*
X63450Y49361D01*
Y52639D01*
X62602Y55806D01*
X60963Y58644D01*
X58644Y60963D01*
X55806Y62602D01*
X52639Y63450D01*
D02*
G37*
G36*
X408019Y61500D02*
X403981D01*
X400020Y60712D01*
X396290Y59167D01*
X392932Y56923D01*
X390077Y54068D01*
X387833Y50710D01*
X386288Y46980D01*
X385500Y43019D01*
Y38981D01*
X386288Y35020D01*
X387833Y31290D01*
X390077Y27932D01*
X392932Y25077D01*
X396290Y22833D01*
X400020Y21288D01*
X403981Y20500D01*
X408019D01*
X411980Y21288D01*
X415710Y22833D01*
X419068Y25077D01*
X421923Y27932D01*
X424167Y31290D01*
X425712Y35020D01*
X426500Y38981D01*
Y43019D01*
X425712Y46980D01*
X424167Y50710D01*
X421923Y54068D01*
X419068Y56923D01*
X415710Y59167D01*
X411980Y60712D01*
X408019Y61500D01*
D02*
G37*
%LPD*%
D76*
X34250Y179000D02*
D03*
D77*
X59650D02*
D03*
D78*
X192000Y484000D02*
D03*
X51000Y457000D02*
D03*
X457000Y51000D02*
D03*
Y457000D02*
D03*
X132000Y484000D02*
D03*
X102000D02*
D03*
X72000D02*
D03*
X457000Y254000D02*
D03*
X51000Y51000D02*
D03*
X162000Y484000D02*
D03*
D79*
X465000Y138000D02*
D03*
Y349000D02*
D03*
D80*
X315000Y203311D02*
D03*
X241500Y478750D02*
D03*
X220968Y339000D02*
D03*
X349911Y39320D02*
D03*
X350161Y52070D02*
D03*
X350607Y63513D02*
D03*
X350161Y75070D02*
D03*
X360411Y74570D02*
D03*
X360857Y63014D02*
D03*
X360411Y51570D02*
D03*
X360161Y38820D02*
D03*
X350911Y90320D02*
D03*
X351161Y103070D02*
D03*
X351607Y114514D02*
D03*
X351161Y126070D02*
D03*
X361411Y125570D02*
D03*
X361857Y114014D02*
D03*
X361411Y102570D02*
D03*
X361161Y89820D02*
D03*
X308000Y46100D02*
D03*
X320750Y45850D02*
D03*
X332193Y45405D02*
D03*
X343750Y45850D02*
D03*
X343250Y35600D02*
D03*
X331693Y35155D02*
D03*
X320250Y35600D02*
D03*
X307500Y35850D02*
D03*
Y84500D02*
D03*
X320250Y84250D02*
D03*
X331693Y83804D02*
D03*
X343250Y84250D02*
D03*
X342750Y74000D02*
D03*
X331194Y73554D02*
D03*
X319750Y74000D02*
D03*
X307000Y74250D02*
D03*
X306320Y53339D02*
D03*
X319070Y53089D02*
D03*
X330513Y52643D02*
D03*
X342070Y53089D02*
D03*
X342570Y63339D02*
D03*
X331013Y62893D02*
D03*
X319570Y63339D02*
D03*
X306820Y63589D02*
D03*
Y105339D02*
D03*
X319570Y105089D02*
D03*
X331013Y104643D02*
D03*
X342570Y105089D02*
D03*
X342070Y94839D02*
D03*
X330513Y94393D02*
D03*
X319070Y94839D02*
D03*
X306320Y95089D02*
D03*
X307000Y116000D02*
D03*
X319750Y115750D02*
D03*
X331194Y115304D02*
D03*
X342750Y115750D02*
D03*
X343250Y126000D02*
D03*
X331693Y125554D02*
D03*
X320250Y126000D02*
D03*
X307500Y126250D02*
D03*
X192905Y69250D02*
D03*
X183138Y69052D02*
D03*
X173250Y65020D02*
D03*
X161750Y64750D02*
D03*
X149500Y63250D02*
D03*
X234398Y422690D02*
D03*
X223373Y415288D02*
D03*
X298715Y489190D02*
D03*
X351500Y488750D02*
D03*
X445113Y472750D02*
D03*
X475000Y447750D02*
D03*
X331500Y400274D02*
D03*
X327000Y392924D02*
D03*
X342703Y406495D02*
D03*
X206542Y332843D02*
D03*
X193292Y330805D02*
D03*
X145000Y264000D02*
D03*
X156752Y276869D02*
D03*
X83952Y262552D02*
D03*
X17462Y347587D02*
D03*
X363500Y449682D02*
D03*
X241197Y308750D02*
D03*
X285250Y446030D02*
D03*
X372500Y440000D02*
D03*
X440352Y374949D02*
D03*
X294500Y454750D02*
D03*
X270921Y437500D02*
D03*
X267761Y319250D02*
D03*
X172000Y147750D02*
D03*
X158750Y132850D02*
D03*
X52118Y197290D02*
D03*
X65473Y198873D02*
D03*
X65619Y215500D02*
D03*
X66659Y224000D02*
D03*
X87000Y475250D02*
D03*
X117080Y493963D02*
D03*
X177000Y492750D02*
D03*
X209500Y489750D02*
D03*
X444999Y421418D02*
D03*
X69000Y463250D02*
D03*
X289250Y269500D02*
D03*
X343677Y360775D02*
D03*
X391028Y361264D02*
D03*
X354750Y339500D02*
D03*
X363284Y389088D02*
D03*
X259492Y353693D02*
D03*
X274414Y352344D02*
D03*
X334750Y326000D02*
D03*
X297250Y385500D02*
D03*
X228424Y209744D02*
D03*
X224129Y188721D02*
D03*
X243500Y244381D02*
D03*
X212000Y174955D02*
D03*
X159750Y177787D02*
D03*
X171400Y173000D02*
D03*
X258939Y182705D02*
D03*
X243939Y182955D02*
D03*
X270189Y187644D02*
D03*
X258939Y209744D02*
D03*
X243939D02*
D03*
X279206Y190705D02*
D03*
X315250Y392363D02*
D03*
X345269Y393919D02*
D03*
X169161Y102103D02*
D03*
X183138D02*
D03*
X172498Y113250D02*
D03*
X95610Y353378D02*
D03*
X184407Y173689D02*
D03*
X146750Y230310D02*
D03*
X350250Y211521D02*
D03*
X344750Y243000D02*
D03*
X332000D02*
D03*
X243500Y257561D02*
D03*
X293674Y244381D02*
D03*
X206956Y397805D02*
D03*
X207706Y432800D02*
D03*
X175750D02*
D03*
X51500Y390689D02*
D03*
X103750Y358378D02*
D03*
X142000Y359750D02*
D03*
X109250Y377668D02*
D03*
X139750Y463508D02*
D03*
X17785Y397960D02*
D03*
X17500Y388019D02*
D03*
Y377710D02*
D03*
Y367710D02*
D03*
Y357460D02*
D03*
X8744Y354901D02*
D03*
X244245Y292311D02*
D03*
X393250Y242500D02*
D03*
X272892Y294750D02*
D03*
X55967Y354628D02*
D03*
X27078Y93504D02*
D03*
X129610Y95565D02*
D03*
X55090Y93504D02*
D03*
X91000Y108500D02*
D03*
X391579Y185091D02*
D03*
X403000Y173750D02*
D03*
Y263500D02*
D03*
X414482Y274431D02*
D03*
X273500Y244381D02*
D03*
X258000D02*
D03*
Y292250D02*
D03*
X363962Y297432D02*
D03*
X232250Y291385D02*
D03*
X264500Y375775D02*
D03*
X375750Y322588D02*
D03*
X145319Y249000D02*
D03*
X160000Y186500D02*
D03*
X84365Y251500D02*
D03*
X22702Y246500D02*
D03*
X52108Y254060D02*
D03*
X102727Y162527D02*
D03*
X66500D02*
D03*
X77704D02*
D03*
X115250D02*
D03*
X142000Y178086D02*
D03*
X130429Y181250D02*
D03*
X114250Y104000D02*
D03*
X72036Y102261D02*
D03*
X41916Y93504D02*
D03*
X55090Y106500D02*
D03*
X91005Y119250D02*
D03*
X129500Y106500D02*
D03*
X403000Y185091D02*
D03*
X403000Y274431D02*
D03*
M02*
